FILE_TYPE = CONNECTIVITY;
{Allegro Design Entry HDL 17.2-2016 S081 (4005846) 1/11/2022}
"PAGE_NUMBER" = 206;
0"NC";
END.
